(kicad_pcb
	(version 20260206)
	(generator "pcbnew")
	(generator_version "10.0")
	(general
		(thickness 1.6)
		(legacy_teardrops no)
	)
	(paper "A4")
	(title_block
		(title "Bryce Canyon_IOM_IOC_16318-2_OCP.brd")
		(comment 1 "Bryce Canyon / footprints 452-458 of 1605")
	)
	(layers
		(0 "F.Cu" signal "TOP")
		(4 "In1.Cu" signal "L2GND")
		(6 "In2.Cu" signal "L3")
		(8 "In3.Cu" signal "L4VCC")
		(10 "In4.Cu" signal "L5VCC")
		(12 "In5.Cu" signal "L6")
		(14 "In6.Cu" signal "L7GND")
		(2 "B.Cu" signal "BOTTOM")
		(9 "F.Adhes" user "F.Adhesive")
		(11 "B.Adhes" user "B.Adhesive")
		(13 "F.Paste" user "Package Geometry/Pastemask Top")
		(15 "B.Paste" user "Package Geometry/Pastemask Bottom")
		(5 "F.SilkS" user "Ref Des/Silkscreen Top")
		(7 "B.SilkS" user "Ref Des/Silkscreen Bottom")
		(1 "F.Mask" user "Board Geometry/Soldermask Top")
		(3 "B.Mask" user "Board Geometry/Soldermask Bottom")
		(17 "Dwgs.User" user "User.Drawings")
		(19 "Cmts.User" user "User.Comments")
		(21 "Eco1.User" user "User.Eco1")
		(23 "Eco2.User" user "User.Eco2")
		(25 "Edge.Cuts" user "Board Geometry/Outline")
		(27 "Margin" user)
		(31 "F.CrtYd" user "Package Geometry/Place Bound Top")
		(29 "B.CrtYd" user "Package Geometry/Place Bound Bottom")
		(35 "F.Fab" user "Ref Des/Assembly Top")
		(33 "B.Fab" user "Ref Des/Assembly Bottom")
	)
	(footprint ""
		(layer "F.Cu")
		(at 92.33154 -173.73092 -90)
		(property "Reference" "U107"
			(at 0 0 270)
			(layer "F.SilkS")
			(hide yes)
			(effects
				(font
					(size 1.27 1.27)
				)
			)
		)
		(property "Value" "SN74CBTLV3245APWR-GP"
			(at -0.889 -6.2738 270)
			(unlocked yes)
			(layer "F.Fab")
			(hide yes)
			(effects
				(font
					(size 1.016 1.016)
					(thickness 0.1524)
				)
			)
		)
		(property "Device Type" "TSOIC20H48"
			(at -0.9144 -7.8994 270)
			(unlocked yes)
			(layer "F.Fab")
			(hide yes)
			(effects
				(font
					(size 1.016 1.016)
					(thickness 0.1524)
				)
			)
		)
		(duplicate_pad_numbers_are_jumpers no)
		(fp_line
			(start -3.556 4.064)
			(end -3.556 1.778)
			(stroke
				(width 0.508)
				(type default)
			)
			(layer "F.SilkS")
		)
		(fp_line
			(start -3.556 1.397)
			(end -3.556 1.778)
			(stroke
				(width 0.2032)
				(type default)
			)
			(layer "F.SilkS")
		)
		(fp_line
			(start 3.175 1.397)
			(end -3.556 1.397)
			(stroke
				(width 0.2032)
				(type default)
			)
			(layer "F.SilkS")
		)
		(fp_line
			(start -2.667 0)
			(end -3.556 0.889)
			(stroke
				(width 0.2032)
				(type default)
			)
			(layer "F.SilkS")
		)
		(fp_line
			(start -2.667 0)
			(end -3.556 -0.889)
			(stroke
				(width 0.2032)
				(type default)
			)
			(layer "F.SilkS")
		)
		(fp_line
			(start -3.556 -1.397)
			(end -3.556 4.064)
			(stroke
				(width 0.2032)
				(type default)
			)
			(layer "F.SilkS")
		)
		(fp_line
			(start -3.556 -1.397)
			(end 3.175 -1.397)
			(stroke
				(width 0.2032)
				(type default)
			)
			(layer "F.SilkS")
		)
		(fp_line
			(start 3.175 -1.397)
			(end 3.175 1.397)
			(stroke
				(width 0.2032)
				(type default)
			)
			(layer "F.SilkS")
		)
		(fp_poly
			(pts
				(xy -3.25628 -1.8542) (xy 3.25628 -1.8542) (xy 3.25628 1.8542) (xy -3.25628 1.8542)
			)
			(stroke
				(width 0)
				(type default)
			)
			(fill yes)
			(layer "F.SilkS")
		)
		(fp_rect
			(start -3.556 3.81)
			(end 3.556 -3.81)
			(stroke
				(width 0)
				(type default)
			)
			(fill no)
			(layer "F.CrtYd")
		)
		(fp_poly
			(pts
				(xy -3.556 -3.81) (xy 3.556 -3.81) (xy 3.556 3.81) (xy -3.556 3.81)
			)
			(stroke
				(width 0)
				(type default)
			)
			(fill no)
			(layer "F.Fab")
		)
		(pad "1" smd rect
			(at -2.92608 2.8194 270)
			(size 0.3556 1.524)
			(layers "F.Cu" "F.Mask" "F.Paste")
			(net "Net_131")
		)
		(pad "2" smd rect
			(at -2.27584 2.8194 270)
			(size 0.3556 1.524)
			(layers "F.Cu" "F.Mask" "F.Paste")
			(net "Net_77")
		)
		(pad "3" smd rect
			(at -1.6256 2.8194 270)
			(size 0.3556 1.524)
			(layers "F.Cu" "F.Mask" "F.Paste")
			(net "Net_79")
		)
		(pad "4" smd rect
			(at -0.97536 2.8194 270)
			(size 0.3556 1.524)
			(layers "F.Cu" "F.Mask" "F.Paste")
			(net "Net_75")
		)
		(pad "5" smd rect
			(at -0.32512 2.8194 270)
			(size 0.3556 1.524)
			(layers "F.Cu" "F.Mask" "F.Paste")
			(net "I2C_DPB_MISC_SCL_OUT")
		)
		(pad "6" smd rect
			(at 0.32512 2.8194 270)
			(size 0.3556 1.524)
			(layers "F.Cu" "F.Mask" "F.Paste")
			(net "I2C_DPB_MISC_SDA_OUT")
		)
		(pad "7" smd rect
			(at 0.97536 2.8194 270)
			(size 0.3556 1.524)
			(layers "F.Cu" "F.Mask" "F.Paste")
			(net "DPB_MISC_ALERT")
		)
		(pad "8" smd rect
			(at 1.6256 2.8194 270)
			(size 0.3556 1.524)
			(layers "F.Cu" "F.Mask" "F.Paste")
			(net "Net_130")
		)
		(pad "9" smd rect
			(at 2.27584 2.8194 270)
			(size 0.3556 1.524)
			(layers "F.Cu" "F.Mask" "F.Paste")
			(net "Net_129")
		)
		(pad "10" smd rect
			(at 2.92608 2.8194 270)
			(size 0.3556 1.524)
			(layers "F.Cu" "F.Mask" "F.Paste")
			(net "GND")
		)
		(pad "11" smd rect
			(at 2.92608 -2.8194 270)
			(size 0.3556 1.524)
			(layers "F.Cu" "F.Mask" "F.Paste")
			(net "Net_128")
		)
		(pad "12" smd rect
			(at 2.27584 -2.8194 270)
			(size 0.3556 1.524)
			(layers "F.Cu" "F.Mask" "F.Paste")
			(net "Net_127")
		)
		(pad "13" smd rect
			(at 1.6256 -2.8194 270)
			(size 0.3556 1.524)
			(layers "F.Cu" "F.Mask" "F.Paste")
			(net "DPB_MISC_ALERT_OUT_R")
		)
		(pad "14" smd rect
			(at 0.97536 -2.8194 270)
			(size 0.3556 1.524)
			(layers "F.Cu" "F.Mask" "F.Paste")
			(net "I2C_DPB_MISC_SDA_R")
		)
		(pad "15" smd rect
			(at 0.32512 -2.8194 270)
			(size 0.3556 1.524)
			(layers "F.Cu" "F.Mask" "F.Paste")
			(net "I2C_DPB_MISC_SCL_R")
		)
		(pad "16" smd rect
			(at -0.32512 -2.8194 270)
			(size 0.3556 1.524)
			(layers "F.Cu" "F.Mask" "F.Paste")
			(net "Net_80")
		)
		(pad "17" smd rect
			(at -0.97536 -2.8194 270)
			(size 0.3556 1.524)
			(layers "F.Cu" "F.Mask" "F.Paste")
			(net "Net_78")
		)
		(pad "18" smd rect
			(at -1.6256 -2.8194 270)
			(size 0.3556 1.524)
			(layers "F.Cu" "F.Mask" "F.Paste")
			(net "Net_76")
		)
		(pad "19" smd rect
			(at -2.27584 -2.8194 270)
			(size 0.3556 1.524)
			(layers "F.Cu" "F.Mask" "F.Paste")
			(net "PWRGD_P3V3_STBY_N_R2")
		)
		(pad "20" smd rect
			(at -2.92608 -2.8194 270)
			(size 0.3556 1.524)
			(layers "F.Cu" "F.Mask" "F.Paste")
			(net "P3V3_STBY")
		)
	)
	(footprint ""
		(layer "F.Cu")
		(at 14.73454 -12.90574 180)
		(property "Reference" "R47"
			(at 0 0 180)
			(layer "F.SilkS")
			(hide yes)
			(effects
				(font
					(size 1.27 1.27)
				)
			)
		)
		(property "Value" "1MR2F-GP"
			(at 0.064008 -3.993896 180)
			(unlocked yes)
			(layer "F.Fab")
			(hide yes)
			(effects
				(font
					(size 1.016 1.016)
					(thickness 0.1524)
				)
			)
		)
		(property "Device Type" "R402H16"
			(at 0.064008 -5.517896 180)
			(unlocked yes)
			(layer "F.Fab")
			(hide yes)
			(effects
				(font
					(size 1.016 1.016)
					(thickness 0.1524)
				)
			)
		)
		(duplicate_pad_numbers_are_jumpers no)
		(fp_line
			(start 0.508 -0.9398)
			(end -0.508 -0.9398)
			(stroke
				(width 0.1524)
				(type default)
			)
			(layer "F.SilkS")
		)
		(fp_line
			(start -0.508 -0.9398)
			(end -0.508 0.9398)
			(stroke
				(width 0.1524)
				(type default)
			)
			(layer "F.SilkS")
		)
		(fp_rect
			(start -0.508 0.9398)
			(end 0.508 -0.9398)
			(stroke
				(width 0)
				(type default)
			)
			(fill no)
			(layer "F.CrtYd")
		)
		(fp_rect
			(start -0.508 0.9398)
			(end 0.508 -0.9398)
			(stroke
				(width 0)
				(type default)
			)
			(fill no)
			(layer "F.Fab")
		)
		(pad "1" smd custom
			(at 0 -0.4445 180)
			(size 0.1397 0.1397)
			(layers "F.Cu" "F.Mask" "F.Paste")
			(net "RST_BTN_GND")
			(options
				(clearance outline)
				(anchor circle)
			)
			(primitives
				(gr_poly
					(pts
						(arc
							(start -0.1778 -0.2794)
							(mid -0.249642 -0.249642)
							(end -0.2794 -0.1778)
						)
						(arc
							(start -0.2794 0.1778)
							(mid -0.249642 0.249642)
							(end -0.1778 0.2794)
						)
						(arc
							(start 0.1778 0.2794)
							(mid 0.249642 0.249642)
							(end 0.2794 0.1778)
						)
						(arc
							(start 0.2794 -0.1778)
							(mid 0.249642 -0.249642)
							(end 0.1778 -0.2794)
						)
					)
					(width 0)
					(fill yes)
				)
			)
		)
		(pad "2" smd custom
			(at 0 0.4445 180)
			(size 0.1397 0.1397)
			(layers "F.Cu" "F.Mask" "F.Paste")
			(net "GND")
			(options
				(clearance outline)
				(anchor circle)
			)
			(primitives
				(gr_poly
					(pts
						(arc
							(start -0.1778 -0.2794)
							(mid -0.249642 -0.249642)
							(end -0.2794 -0.1778)
						)
						(arc
							(start -0.2794 0.1778)
							(mid -0.249642 0.249642)
							(end -0.1778 0.2794)
						)
						(arc
							(start 0.1778 0.2794)
							(mid 0.249642 0.249642)
							(end 0.2794 0.1778)
						)
						(arc
							(start 0.2794 -0.1778)
							(mid 0.249642 -0.249642)
							(end 0.1778 -0.2794)
						)
					)
					(width 0)
					(fill yes)
				)
			)
		)
	)
	(footprint ""
		(layer "F.Cu")
		(at 72.04964 -164.5793 90)
		(property "Reference" "R541"
			(at 0 0 90)
			(layer "F.SilkS")
			(hide yes)
			(effects
				(font
					(size 1.27 1.27)
				)
			)
		)
		(property "Value" "4K75R2F-1-GP"
			(at 0.064008 -3.993896 90)
			(unlocked yes)
			(layer "F.Fab")
			(hide yes)
			(effects
				(font
					(size 1.016 1.016)
					(thickness 0.1524)
				)
			)
		)
		(property "Device Type" "R402H16"
			(at 0.064008 -5.517896 90)
			(unlocked yes)
			(layer "F.Fab")
			(hide yes)
			(effects
				(font
					(size 1.016 1.016)
					(thickness 0.1524)
				)
			)
		)
		(duplicate_pad_numbers_are_jumpers no)
		(fp_line
			(start 0.508 -0.9398)
			(end -0.508 -0.9398)
			(stroke
				(width 0.1524)
				(type default)
			)
			(layer "F.SilkS")
		)
		(fp_line
			(start -0.508 -0.9398)
			(end -0.508 0.9398)
			(stroke
				(width 0.1524)
				(type default)
			)
			(layer "F.SilkS")
		)
		(fp_rect
			(start -0.508 0.9398)
			(end 0.508 -0.9398)
			(stroke
				(width 0)
				(type default)
			)
			(fill no)
			(layer "F.CrtYd")
		)
		(fp_rect
			(start -0.508 0.9398)
			(end 0.508 -0.9398)
			(stroke
				(width 0)
				(type default)
			)
			(fill no)
			(layer "F.Fab")
		)
		(pad "1" smd custom
			(at 0 -0.4445 90)
			(size 0.1397 0.1397)
			(layers "F.Cu" "F.Mask" "F.Paste")
			(net "P3V3_STBY")
			(options
				(clearance outline)
				(anchor circle)
			)
			(primitives
				(gr_poly
					(pts
						(arc
							(start -0.1778 -0.2794)
							(mid -0.249642 -0.249642)
							(end -0.2794 -0.1778)
						)
						(arc
							(start -0.2794 0.1778)
							(mid -0.249642 0.249642)
							(end -0.1778 0.2794)
						)
						(arc
							(start 0.1778 0.2794)
							(mid 0.249642 0.249642)
							(end 0.2794 0.1778)
						)
						(arc
							(start 0.2794 -0.1778)
							(mid 0.249642 -0.249642)
							(end 0.1778 -0.2794)
						)
					)
					(width 0)
					(fill yes)
				)
			)
		)
		(pad "2" smd custom
			(at 0 0.4445 90)
			(size 0.1397 0.1397)
			(layers "F.Cu" "F.Mask" "F.Paste")
			(net "TPS74801_P1V15_STBY_EN")
			(options
				(clearance outline)
				(anchor circle)
			)
			(primitives
				(gr_poly
					(pts
						(arc
							(start -0.1778 -0.2794)
							(mid -0.249642 -0.249642)
							(end -0.2794 -0.1778)
						)
						(arc
							(start -0.2794 0.1778)
							(mid -0.249642 0.249642)
							(end -0.1778 0.2794)
						)
						(arc
							(start 0.1778 0.2794)
							(mid 0.249642 0.249642)
							(end 0.2794 0.1778)
						)
						(arc
							(start 0.2794 -0.1778)
							(mid 0.249642 -0.249642)
							(end 0.1778 -0.2794)
						)
					)
					(width 0)
					(fill yes)
				)
			)
		)
	)
	(footprint ""
		(layer "F.Cu")
		(at 42.7482 -157.9626)
		(property "Reference" "TP187"
			(at 0 0 0)
			(layer "F.SilkS")
			(hide yes)
			(effects
				(font
					(size 1.27 1.27)
				)
			)
		)
		(property "Value" "TPAD28-2-GP"
			(at -0.0127 -1.6637 0)
			(unlocked yes)
			(layer "F.Fab")
			(hide yes)
			(effects
				(font
					(size 1.016 1.016)
					(thickness 0.1524)
				)
			)
		)
		(property "Device Type" "TPAD28"
			(at -0.0127 -3.1877 0)
			(unlocked yes)
			(layer "F.Fab")
			(hide yes)
			(effects
				(font
					(size 1.016 1.016)
					(thickness 0.1524)
				)
			)
		)
		(duplicate_pad_numbers_are_jumpers no)
		(fp_poly
			(pts
				(arc
					(start 0.3556 0)
					(mid -0.3556 0)
					(end 0.3556 0)
				)
			)
			(stroke
				(width 0)
				(type default)
			)
			(fill no)
			(layer "F.CrtYd")
		)
		(fp_poly
			(pts
				(arc
					(start 0.6096 0)
					(mid -0.6096 0)
					(end 0.6096 0)
				)
			)
			(stroke
				(width 0)
				(type default)
			)
			(fill no)
			(layer "F.Fab")
		)
		(pad "1" smd circle
			(at 0 0)
			(size 0.7112 0.7112)
			(layers "F.Cu" "F.Mask" "F.Paste")
			(net "TP_BMC_GPIOL1")
		)
	)
	(footprint ""
		(layer "F.Cu")
		(at 76.1746 -167.4114 180)
		(property "Reference" "C524"
			(at 0 0 180)
			(layer "F.SilkS")
			(hide yes)
			(effects
				(font
					(size 1.27 1.27)
				)
			)
		)
		(property "Value" "SC1U16V2KX-7-GP"
			(at 1.7526 -1.6002 180)
			(unlocked yes)
			(layer "F.Fab")
			(hide yes)
			(effects
				(font
					(size 1.016 1.016)
					(thickness 0.1524)
				)
			)
		)
		(property "Device Type" "C402-TO0D2H24"
			(at 1.7526 -3.1242 180)
			(unlocked yes)
			(layer "F.Fab")
			(hide yes)
			(effects
				(font
					(size 1.016 1.016)
					(thickness 0.1524)
				)
			)
		)
		(duplicate_pad_numbers_are_jumpers no)
		(fp_rect
			(start -0.4826 0.889)
			(end 0.4826 -0.889)
			(stroke
				(width 0)
				(type default)
			)
			(fill no)
			(layer "F.CrtYd")
		)
		(fp_rect
			(start -0.4826 0.889)
			(end 0.4826 -0.889)
			(stroke
				(width 0)
				(type default)
			)
			(fill no)
			(layer "F.Fab")
		)
		(pad "1" smd custom
			(at 0 -0.4572 180)
			(size 0.1524 0.1524)
			(layers "F.Cu" "F.Mask" "F.Paste")
			(net "P1V15_STBY_PG")
			(options
				(clearance outline)
				(anchor circle)
			)
			(primitives
				(gr_poly
					(pts
						(arc
							(start -0.254 0.3048)
							(mid -0.325842 0.275042)
							(end -0.3556 0.2032)
						)
						(arc
							(start -0.3556 -0.2032)
							(mid -0.325842 -0.275042)
							(end -0.254 -0.3048)
						)
						(arc
							(start 0.254 -0.3048)
							(mid 0.325842 -0.275042)
							(end 0.3556 -0.2032)
						)
						(arc
							(start 0.3556 0.2032)
							(mid 0.325842 0.275042)
							(end 0.254 0.3048)
						)
					)
					(width 0)
					(fill yes)
				)
			)
		)
		(pad "2" smd custom
			(at 0 0.4572 180)
			(size 0.1524 0.1524)
			(layers "F.Cu" "F.Mask" "F.Paste")
			(net "GND")
			(options
				(clearance outline)
				(anchor circle)
			)
			(primitives
				(gr_poly
					(pts
						(arc
							(start -0.254 0.3048)
							(mid -0.325842 0.275042)
							(end -0.3556 0.2032)
						)
						(arc
							(start -0.3556 -0.2032)
							(mid -0.325842 -0.275042)
							(end -0.254 -0.3048)
						)
						(arc
							(start 0.254 -0.3048)
							(mid 0.325842 -0.275042)
							(end 0.3556 -0.2032)
						)
						(arc
							(start 0.3556 0.2032)
							(mid 0.325842 0.275042)
							(end 0.254 0.3048)
						)
					)
					(width 0)
					(fill yes)
				)
			)
		)
	)
	(footprint ""
		(layer "F.Cu")
		(at 88.773 -130.0226 -90)
		(property "Reference" "R421"
			(at 0 0 270)
			(layer "F.SilkS")
			(hide yes)
			(effects
				(font
					(size 1.27 1.27)
				)
			)
		)
		(property "Value" "10KR2F-2-GP"
			(at 0.064008 -3.993896 270)
			(unlocked yes)
			(layer "F.Fab")
			(hide yes)
			(effects
				(font
					(size 1.016 1.016)
					(thickness 0.1524)
				)
			)
		)
		(property "Device Type" "R402H16"
			(at 0.064008 -5.517896 270)
			(unlocked yes)
			(layer "F.Fab")
			(hide yes)
			(effects
				(font
					(size 1.016 1.016)
					(thickness 0.1524)
				)
			)
		)
		(duplicate_pad_numbers_are_jumpers no)
		(fp_line
			(start -0.508 -0.9398)
			(end -0.508 0.9398)
			(stroke
				(width 0.1524)
				(type default)
			)
			(layer "F.SilkS")
		)
		(fp_line
			(start 0.508 -0.9398)
			(end -0.508 -0.9398)
			(stroke
				(width 0.1524)
				(type default)
			)
			(layer "F.SilkS")
		)
		(fp_rect
			(start -0.508 0.9398)
			(end 0.508 -0.9398)
			(stroke
				(width 0)
				(type default)
			)
			(fill no)
			(layer "F.CrtYd")
		)
		(fp_rect
			(start -0.508 0.9398)
			(end 0.508 -0.9398)
			(stroke
				(width 0)
				(type default)
			)
			(fill no)
			(layer "F.Fab")
		)
		(pad "1" smd custom
			(at 0 -0.4445 270)
			(size 0.1397 0.1397)
			(layers "F.Cu" "F.Mask" "F.Paste")
			(net "UART_SEL_MUX")
			(options
				(clearance outline)
				(anchor circle)
			)
			(primitives
				(gr_poly
					(pts
						(arc
							(start -0.1778 -0.2794)
							(mid -0.249642 -0.249642)
							(end -0.2794 -0.1778)
						)
						(arc
							(start -0.2794 0.1778)
							(mid -0.249642 0.249642)
							(end -0.1778 0.2794)
						)
						(arc
							(start 0.1778 0.2794)
							(mid 0.249642 0.249642)
							(end 0.2794 0.1778)
						)
						(arc
							(start 0.2794 -0.1778)
							(mid 0.249642 -0.249642)
							(end 0.1778 -0.2794)
						)
					)
					(width 0)
					(fill yes)
				)
			)
		)
		(pad "2" smd custom
			(at 0 0.4445 270)
			(size 0.1397 0.1397)
			(layers "F.Cu" "F.Mask" "F.Paste")
			(net "GND")
			(options
				(clearance outline)
				(anchor circle)
			)
			(primitives
				(gr_poly
					(pts
						(arc
							(start -0.1778 -0.2794)
							(mid -0.249642 -0.249642)
							(end -0.2794 -0.1778)
						)
						(arc
							(start -0.2794 0.1778)
							(mid -0.249642 0.249642)
							(end -0.1778 0.2794)
						)
						(arc
							(start 0.1778 0.2794)
							(mid 0.249642 0.249642)
							(end 0.2794 0.1778)
						)
						(arc
							(start 0.2794 -0.1778)
							(mid 0.249642 -0.249642)
							(end 0.1778 -0.2794)
						)
					)
					(width 0)
					(fill yes)
				)
			)
		)
	)
	(footprint ""
		(layer "F.Cu")
		(at 165.481 -133.858)
		(property "Reference" "C204"
			(at 0 0 0)
			(layer "F.SilkS")
			(hide yes)
			(effects
				(font
					(size 1.27 1.27)
				)
			)
		)
		(property "Value" "SC10U16V5KX-7-GP-U"
			(at -0.0762 -6.1214 0)
			(unlocked yes)
			(layer "F.Fab")
			(hide yes)
			(effects
				(font
					(size 1.016 1.016)
					(thickness 0.1524)
				)
			)
		)
		(property "Device Type" "C805H58"
			(at -0.0762 -8.1534 0)
			(unlocked yes)
			(layer "F.Fab")
			(hide yes)
			(effects
				(font
					(size 1.016 1.016)
					(thickness 0.1524)
				)
			)
		)
		(duplicate_pad_numbers_are_jumpers no)
		(fp_line
			(start 0.635 0)
			(end -0.635 0)
			(stroke
				(width 0.508)
				(type default)
			)
			(layer "F.SilkS")
		)
		(fp_rect
			(start -0.9652 1.778)
			(end 0.9652 -1.778)
			(stroke
				(width 0)
				(type default)
			)
			(fill no)
			(layer "F.CrtYd")
		)
		(fp_poly
			(pts
				(xy -0.9652 -1.778) (xy 0.9652 -1.778) (xy 0.9652 1.778) (xy -0.9652 1.778)
			)
			(stroke
				(width 0)
				(type default)
			)
			(fill no)
			(layer "F.Fab")
		)
		(pad "1" smd rect
			(at 0 -0.9652)
			(size 1.397 1.143)
			(layers "F.Cu" "F.Mask" "F.Paste")
			(net "P12V_STBY_VIN_PU4")
		)
		(pad "2" smd rect
			(at 0 0.9652)
			(size 1.397 1.143)
			(layers "F.Cu" "F.Mask" "F.Paste")
			(net "GND")
		)
	)
)
